# T6G (Grand Teton) — schematic netlist excerpt (pin names and nets, part order shuffled) for the footprints in the layout excerpt that follows; sources: Cadence DE-HDL packaged netlist, KiCad conversion of 04192023_DAF0TMB3IC0_F0TG_MB_C_brd_V02_OCP.brd

R1011  Q_RES  0 5% CHIP  pkg 0603LF  page 290 : A = P0V9_CPU0_RT1_2A_2D ; B = P0V9_CPU0_RT1_2A
C2248  Q_CAP  22UF 4V 20% X6S  pkg C0402  page 69 : A = PVDDCR_CPU1_P0 ; B = GND

(kicad_pcb
	(version 20260206)
	(generator "pcbnew")
	(generator_version "10.0")
	(general
		(thickness 1.6)
		(legacy_teardrops no)
	)
	(paper "A4")
	(title_block
		(title "04192023_DAF0TMB3IC0_F0TG_MB_C_brd_V02_OCP.brd")
		(comment 1 "Grand Teton / footprints 6182-6183 of 8354")
	)
	(layers
		(0 "F.Cu" signal "TOP")
		(4 "In1.Cu" signal "GND")
		(6 "In2.Cu" signal "IN1")
		(8 "In3.Cu" signal "GND1")
		(10 "In4.Cu" signal "IN2")
		(12 "In5.Cu" signal "GND2")
		(14 "In6.Cu" signal "IN3")
		(16 "In7.Cu" signal "GND3")
		(18 "In8.Cu" signal "VCC")
		(20 "In9.Cu" signal "VCC1")
		(22 "In10.Cu" signal "GND4")
		(24 "In11.Cu" signal "IN4")
		(26 "In12.Cu" signal "GND5")
		(28 "In13.Cu" signal "IN5")
		(30 "In14.Cu" signal "GND6")
		(32 "In15.Cu" signal "IN6")
		(34 "In16.Cu" signal "GND7")
		(2 "B.Cu" signal "BOTTOM")
		(9 "F.Adhes" user "F.Adhesive")
		(11 "B.Adhes" user "B.Adhesive")
		(13 "F.Paste" user "Package Geometry/Pastemask Top")
		(15 "B.Paste" user "Package Geometry/Pastemask Bottom")
		(5 "F.SilkS" user "Ref Des/Silkscreen Top")
		(7 "B.SilkS" user "Ref Des/Silkscreen Bottom")
		(1 "F.Mask" user "Board Geometry/Soldermask Top")
		(3 "B.Mask" user "Board Geometry/Soldermask Bottom")
		(17 "Dwgs.User" user "User.Drawings")
		(19 "Cmts.User" user "User.Comments")
		(21 "Eco1.User" user "User.Eco1")
		(23 "Eco2.User" user "User.Eco2")
		(25 "Edge.Cuts" user "Board Geometry/Outline")
		(27 "Margin" user)
		(31 "F.CrtYd" user "Package Geometry/Place Bound Top")
		(29 "B.CrtYd" user "Package Geometry/Place Bound Bottom")
		(35 "F.Fab" user "Ref Des/Assembly Top")
		(33 "B.Fab" user "Ref Des/Assembly Bottom")
	)
	(footprint ""
		(layer "B.Cu")
		(at 329.889358 -401.624546 180)
		(property "Reference" "R1011"
			(at 0 0 0)
			(layer "B.SilkS")
			(hide yes)
			(effects
				(font
					(size 1.27 1.27)
				)
				(justify mirror)
			)
		)
		(property "Value" ""
			(at 0 0 0)
			(layer "B.Fab")
			(effects
				(font
					(size 1.27 1.27)
				)
				(justify mirror)
			)
		)
		(duplicate_pad_numbers_are_jumpers no)
		(fp_line
			(start 1.2954 0.5842)
			(end 1.2954 -0.5842)
			(stroke
				(width 0.1524)
				(type default)
			)
			(layer "B.SilkS")
		)
		(fp_line
			(start 1.2954 -0.5842)
			(end -1.2954 -0.5842)
			(stroke
				(width 0.1524)
				(type default)
			)
			(layer "B.SilkS")
		)
		(fp_line
			(start -1.2954 0.5842)
			(end 1.2954 0.5842)
			(stroke
				(width 0.1524)
				(type default)
			)
			(layer "B.SilkS")
		)
		(fp_line
			(start -1.2954 -0.5842)
			(end -1.2954 0.5842)
			(stroke
				(width 0.1524)
				(type default)
			)
			(layer "B.SilkS")
		)
		(fp_line
			(start 1.1938 0.4064)
			(end 1.1938 -0.406654)
			(stroke
				(width 0.1)
				(type default)
			)
			(layer "B.Fab")
		)
		(fp_line
			(start 1.1938 -0.406654)
			(end 0.8636 -0.406654)
			(stroke
				(width 0.1)
				(type default)
			)
			(layer "B.Fab")
		)
		(fp_line
			(start 0.8636 0.4572)
			(end 0.8636 0.4318)
			(stroke
				(width 0.1)
				(type default)
			)
			(layer "B.Fab")
		)
		(fp_line
			(start 0.8636 0.4318)
			(end 0.8636 0.4064)
			(stroke
				(width 0.1)
				(type default)
			)
			(layer "B.Fab")
		)
		(fp_line
			(start 0.8636 0.4064)
			(end 1.1938 0.4064)
			(stroke
				(width 0.1)
				(type default)
			)
			(layer "B.Fab")
		)
		(fp_line
			(start 0.8636 -0.406654)
			(end 0.8636 -0.4572)
			(stroke
				(width 0.1)
				(type default)
			)
			(layer "B.Fab")
		)
		(fp_line
			(start 0.8636 -0.4572)
			(end -0.8636 -0.4572)
			(stroke
				(width 0.1)
				(type default)
			)
			(layer "B.Fab")
		)
		(fp_line
			(start -0.8636 0.4572)
			(end 0.8636 0.4572)
			(stroke
				(width 0.1)
				(type default)
			)
			(layer "B.Fab")
		)
		(fp_line
			(start -0.8636 0.4064)
			(end -0.8636 0.4572)
			(stroke
				(width 0.1)
				(type default)
			)
			(layer "B.Fab")
		)
		(fp_line
			(start -0.8636 -0.406654)
			(end -1.1938 -0.406654)
			(stroke
				(width 0.1)
				(type default)
			)
			(layer "B.Fab")
		)
		(fp_line
			(start -0.8636 -0.4572)
			(end -0.8636 -0.406654)
			(stroke
				(width 0.1)
				(type default)
			)
			(layer "B.Fab")
		)
		(fp_line
			(start -1.1938 0.4064)
			(end -0.8636 0.4064)
			(stroke
				(width 0.1)
				(type default)
			)
			(layer "B.Fab")
		)
		(fp_line
			(start -1.1938 -0.406654)
			(end -1.1938 0.4064)
			(stroke
				(width 0.1)
				(type default)
			)
			(layer "B.Fab")
		)
		(pad "1" smd rect
			(at 0.7366 0 90)
			(size 0.7112 0.8128)
			(layers "B.Cu" "B.Mask" "B.Paste")
			(net "P0V9_CPU0_RT1_2A_2D")
		)
		(pad "2" smd rect
			(at -0.7366 0 90)
			(size 0.7112 0.8128)
			(layers "B.Cu" "B.Mask" "B.Paste")
			(net "P0V9_CPU0_RT1_2A")
		)
	)
	(footprint ""
		(layer "B.Cu")
		(at 362.407454 -268.41831)
		(property "Reference" "C2248"
			(at 0 0 0)
			(layer "B.SilkS")
			(hide yes)
			(effects
				(font
					(size 1.27 1.27)
				)
				(justify mirror)
			)
		)
		(property "Value" ""
			(at 0 0 0)
			(layer "B.Fab")
			(effects
				(font
					(size 1.27 1.27)
				)
				(justify mirror)
			)
		)
		(duplicate_pad_numbers_are_jumpers no)
		(fp_line
			(start -0.7874 -0.4064)
			(end -0.7874 0.4064)
			(stroke
				(width 0.1524)
				(type default)
			)
			(layer "B.SilkS")
		)
		(fp_line
			(start -0.7874 0.4064)
			(end 0.7874 0.4064)
			(stroke
				(width 0.1524)
				(type default)
			)
			(layer "B.SilkS")
		)
		(fp_line
			(start 0.7874 -0.4064)
			(end -0.7874 -0.4064)
			(stroke
				(width 0.1524)
				(type default)
			)
			(layer "B.SilkS")
		)
		(fp_line
			(start 0.7874 0.4064)
			(end 0.7874 -0.4064)
			(stroke
				(width 0.1524)
				(type default)
			)
			(layer "B.SilkS")
		)
		(fp_line
			(start -0.67945 -0.3048)
			(end -0.67945 0.3048)
			(stroke
				(width 0.1)
				(type default)
			)
			(layer "B.Fab")
		)
		(fp_line
			(start -0.67945 0.3048)
			(end -0.120396 0.3048)
			(stroke
				(width 0.1)
				(type default)
			)
			(layer "B.Fab")
		)
		(fp_line
			(start -0.12065 -0.3048)
			(end -0.67945 -0.3048)
			(stroke
				(width 0.1)
				(type default)
			)
			(layer "B.Fab")
		)
		(fp_line
			(start -0.12065 -0.2794)
			(end -0.12065 -0.3048)
			(stroke
				(width 0.1)
				(type default)
			)
			(layer "B.Fab")
		)
		(fp_line
			(start -0.120396 0.2794)
			(end 0.12065 0.2794)
			(stroke
				(width 0.1)
				(type default)
			)
			(layer "B.Fab")
		)
		(fp_line
			(start -0.120396 0.3048)
			(end -0.120396 0.2794)
			(stroke
				(width 0.1)
				(type default)
			)
			(layer "B.Fab")
		)
		(fp_line
			(start 0.12065 -0.305054)
			(end 0.12065 -0.2794)
			(stroke
				(width 0.1)
				(type default)
			)
			(layer "B.Fab")
		)
		(fp_line
			(start 0.12065 -0.2794)
			(end -0.12065 -0.2794)
			(stroke
				(width 0.1)
				(type default)
			)
			(layer "B.Fab")
		)
		(fp_line
			(start 0.12065 0.2794)
			(end 0.12065 0.3048)
			(stroke
				(width 0.1)
				(type default)
			)
			(layer "B.Fab")
		)
		(fp_line
			(start 0.12065 0.3048)
			(end 0.67945 0.3048)
			(stroke
				(width 0.1)
				(type default)
			)
			(layer "B.Fab")
		)
		(fp_line
			(start 0.67945 -0.305054)
			(end 0.12065 -0.305054)
			(stroke
				(width 0.1)
				(type default)
			)
			(layer "B.Fab")
		)
		(fp_line
			(start 0.67945 0.3048)
			(end 0.67945 -0.305054)
			(stroke
				(width 0.1)
				(type default)
			)
			(layer "B.Fab")
		)
		(pad "1" smd circle
			(at 0.40005 0 180)
			(size 0 0)
			(layers "B.Cu" "B.Mask" "B.Paste")
			(net "PVDDCR_CPU1_P0")
		)
		(pad "2" smd circle
			(at -0.40005 0 180)
			(size 0 0)
			(layers "B.Cu" "B.Mask" "B.Paste")
			(net "GND")
		)
	)
)
